(kicad_pcb
	(version 20260206)
	(generator "pcbnew")
	(generator_version "10.0")
	(general
		(thickness 1.6)
		(legacy_teardrops no)
	)
	(paper "A4")
	(title_block
		(title "01162023_DA0F0TEBIF0_F0T_Expander_BD_F_brd_V02_OCP.brd")
		(comment 1 "Grand Teton / footprint 6602 of 9728 (PEX1), pads 1190-1307 of 2397")
	)
	(layers
		(0 "F.Cu" signal "TOP")
		(4 "In1.Cu" signal "GND")
		(6 "In2.Cu" signal "VCC")
		(8 "In3.Cu" signal "VCC1")
		(10 "In4.Cu" signal "GND1")
		(12 "In5.Cu" signal "IN1")
		(14 "In6.Cu" signal "GND2")
		(16 "In7.Cu" signal "IN2")
		(18 "In8.Cu" signal "GND3")
		(20 "In9.Cu" signal "IN3")
		(22 "In10.Cu" signal "GND4")
		(24 "In11.Cu" signal "IN4")
		(26 "In12.Cu" signal "GND5")
		(28 "In13.Cu" signal "IN5")
		(30 "In14.Cu" signal "GND6")
		(32 "In15.Cu" signal "IN6")
		(34 "In16.Cu" signal "GND7")
		(2 "B.Cu" signal "BOTTOM")
		(9 "F.Adhes" user "F.Adhesive")
		(11 "B.Adhes" user "B.Adhesive")
		(13 "F.Paste" user "Package Geometry/Pastemask Top")
		(15 "B.Paste" user "Package Geometry/Pastemask Bottom")
		(5 "F.SilkS" user "Ref Des/Silkscreen Top")
		(7 "B.SilkS" user "Ref Des/Silkscreen Bottom")
		(1 "F.Mask" user "Board Geometry/Soldermask Top")
		(3 "B.Mask" user "Board Geometry/Soldermask Bottom")
		(17 "Dwgs.User" user "User.Drawings")
		(19 "Cmts.User" user "User.Comments")
		(21 "Eco1.User" user "User.Eco1")
		(23 "Eco2.User" user "User.Eco2")
		(25 "Edge.Cuts" user "Board Geometry/Outline")
		(27 "Margin" user)
		(31 "F.CrtYd" user "Package Geometry/Place Bound Top")
		(29 "B.CrtYd" user "Package Geometry/Place Bound Bottom")
		(35 "F.Fab" user "Ref Des/Assembly Top")
		(33 "B.Fab" user "Ref Des/Assembly Bottom")
	)
	(footprint ""
		(layer "F.Cu")
		(at 175.749966 -295.89984)
		(property "Reference" "PEX1"
			(at -3.353562 35.593274 0)
			(unlocked yes)
			(layer "F.SilkS")
			(effects
				(font
					(size 2.032 1.524)
					(thickness 0.1524)
				)
				(justify left)
			)
		)
		(property "Value" ""
			(at 0 0 0)
			(layer "F.Fab")
			(effects
				(font
					(size 1.27 1.27)
				)
			)
		)
		(duplicate_pad_numbers_are_jumpers no)
		(pad "BC16" smd circle
			(at -8.549894 17.100042)
			(size 0.4572 0.4572)
			(layers "F.Cu" "F.Mask" "F.Paste")
			(net "GND")
		)
		(pad "BC17" smd circle
			(at -7.599934 17.100042)
			(size 0.4572 0.4572)
			(layers "F.Cu" "F.Mask" "F.Paste")
			(net "P5E_PEX1_STN2_TX_DP<39>")
		)
		(pad "BC18" smd circle
			(at -6.649974 17.100042)
			(size 0.4572 0.4572)
			(layers "F.Cu" "F.Mask" "F.Paste")
			(net "GND")
		)
		(pad "BC19" smd circle
			(at -5.700014 17.100042)
			(size 0.4572 0.4572)
			(layers "F.Cu" "F.Mask" "F.Paste")
			(net "P5E_PEX1_STN2_TX_DP<37>")
		)
		(pad "BC20" smd circle
			(at -4.750054 17.100042)
			(size 0.4572 0.4572)
			(layers "F.Cu" "F.Mask" "F.Paste")
			(net "GND")
		)
		(pad "BC21" smd circle
			(at -3.800094 17.100042)
			(size 0.4572 0.4572)
			(layers "F.Cu" "F.Mask" "F.Paste")
			(net "P5E_PEX1_STN2_TX_DP<35>")
		)
		(pad "BC22" smd circle
			(at -2.84988 17.100042)
			(size 0.4572 0.4572)
			(layers "F.Cu" "F.Mask" "F.Paste")
			(net "GND")
		)
		(pad "BC23" smd circle
			(at -1.89992 17.100042)
			(size 0.4572 0.4572)
			(layers "F.Cu" "F.Mask" "F.Paste")
			(net "P5E_PEX1_STN2_TX_DP<33>")
		)
		(pad "BC24" smd circle
			(at -0.94996 17.100042)
			(size 0.4572 0.4572)
			(layers "F.Cu" "F.Mask" "F.Paste")
			(net "GND")
		)
		(pad "BC25" smd circle
			(at 0 17.100042)
			(size 0.4572 0.4572)
			(layers "F.Cu" "F.Mask" "F.Paste")
			(net "P5E_PEX1_STN1_TX_DP<16>")
		)
		(pad "BC26" smd circle
			(at 0.94996 17.100042)
			(size 0.4572 0.4572)
			(layers "F.Cu" "F.Mask" "F.Paste")
			(net "GND")
		)
		(pad "BC27" smd circle
			(at 1.89992 17.100042)
			(size 0.4572 0.4572)
			(layers "F.Cu" "F.Mask" "F.Paste")
			(net "P5E_PEX1_STN1_TX_DP<18>")
		)
		(pad "BC28" smd circle
			(at 2.84988 17.100042)
			(size 0.4572 0.4572)
			(layers "F.Cu" "F.Mask" "F.Paste")
			(net "GND")
		)
		(pad "BC29" smd circle
			(at 3.800094 17.100042)
			(size 0.4572 0.4572)
			(layers "F.Cu" "F.Mask" "F.Paste")
			(net "P5E_PEX1_STN1_TX_DP<20>")
		)
		(pad "BC30" smd circle
			(at 4.750054 17.100042)
			(size 0.4572 0.4572)
			(layers "F.Cu" "F.Mask" "F.Paste")
			(net "GND")
		)
		(pad "BC31" smd circle
			(at 5.700014 17.100042)
			(size 0.4572 0.4572)
			(layers "F.Cu" "F.Mask" "F.Paste")
			(net "P5E_PEX1_STN1_TX_DP<22>")
		)
		(pad "BC32" smd circle
			(at 6.649974 17.100042)
			(size 0.4572 0.4572)
			(layers "F.Cu" "F.Mask" "F.Paste")
			(net "GND")
		)
		(pad "BC33" smd circle
			(at 7.599934 17.100042)
			(size 0.4572 0.4572)
			(layers "F.Cu" "F.Mask" "F.Paste")
			(net "P5E_PEX1_STN1_TX_DP<24>")
		)
		(pad "BC34" smd circle
			(at 8.549894 17.100042)
			(size 0.4572 0.4572)
			(layers "F.Cu" "F.Mask" "F.Paste")
			(net "GND")
		)
		(pad "BC35" smd circle
			(at 9.500108 17.100042)
			(size 0.4572 0.4572)
			(layers "F.Cu" "F.Mask" "F.Paste")
			(net "P5E_PEX1_STN1_TX_DP<26>")
		)
		(pad "BC36" smd circle
			(at 10.450068 17.100042)
			(size 0.4572 0.4572)
			(layers "F.Cu" "F.Mask" "F.Paste")
			(net "GND")
		)
		(pad "BC37" smd circle
			(at 11.400028 17.100042)
			(size 0.4572 0.4572)
			(layers "F.Cu" "F.Mask" "F.Paste")
			(net "P5E_PEX1_STN1_TX_DP<28>")
		)
		(pad "BC38" smd circle
			(at 12.349988 17.100042)
			(size 0.4572 0.4572)
			(layers "F.Cu" "F.Mask" "F.Paste")
			(net "GND")
		)
		(pad "BC39" smd circle
			(at 13.299948 17.100042)
			(size 0.4572 0.4572)
			(layers "F.Cu" "F.Mask" "F.Paste")
			(net "P5E_PEX1_STN1_TX_DP<30>")
		)
		(pad "BC40" smd circle
			(at 14.249908 17.100042)
			(size 0.4572 0.4572)
			(layers "F.Cu" "F.Mask" "F.Paste")
			(net "GND")
		)
		(pad "BC41" smd circle
			(at 15.200122 17.100042)
			(size 0.4572 0.4572)
			(layers "F.Cu" "F.Mask" "F.Paste")
			(net "P5E_PEX1_STN0_TX_DP<15>")
		)
		(pad "BC42" smd circle
			(at 16.150082 17.100042)
			(size 0.4572 0.4572)
			(layers "F.Cu" "F.Mask" "F.Paste")
			(net "GND")
		)
		(pad "BC43" smd circle
			(at 17.100042 17.100042)
			(size 0.4572 0.4572)
			(layers "F.Cu" "F.Mask" "F.Paste")
			(net "P5E_PEX1_STN0_TX_DP<13>")
		)
		(pad "BC44" smd circle
			(at 18.050002 17.100042)
			(size 0.4572 0.4572)
			(layers "F.Cu" "F.Mask" "F.Paste")
			(net "GND")
		)
		(pad "BC45" smd circle
			(at 18.999962 17.100042)
			(size 0.4572 0.4572)
			(layers "F.Cu" "F.Mask" "F.Paste")
			(net "P5E_PEX1_STN0_TX_DP<11>")
		)
		(pad "BC46" smd circle
			(at 19.949922 17.100042)
			(size 0.4572 0.4572)
			(layers "F.Cu" "F.Mask" "F.Paste")
			(net "GND")
		)
		(pad "BC47" smd circle
			(at 20.899882 17.100042)
			(size 0.4572 0.4572)
			(layers "F.Cu" "F.Mask" "F.Paste")
			(net "P5E_PEX1_STN0_TX_DP<9>")
		)
		(pad "BC48" smd circle
			(at 21.850096 17.100042)
			(size 0.4572 0.4572)
			(layers "F.Cu" "F.Mask" "F.Paste")
			(net "GND")
		)
		(pad "BC49" smd circle
			(at 22.800056 17.100042)
			(size 0.4572 0.4572)
			(layers "F.Cu" "F.Mask" "F.Paste")
			(net "GND")
		)
		(pad "BD1" smd circle
			(at -22.800056 18.050002)
			(size 0.4572 0.4572)
			(layers "F.Cu" "F.Mask" "F.Paste")
			(net "GND")
		)
		(pad "BD2" smd circle
			(at -21.850096 18.050002)
			(size 0.4572 0.4572)
			(layers "F.Cu" "F.Mask" "F.Paste")
			(net "GND")
		)
		(pad "BD3" smd circle
			(at -20.899882 18.050002)
			(size 0.4572 0.4572)
			(layers "F.Cu" "F.Mask" "F.Paste")
			(net "Net_1686")
		)
		(pad "BD4" smd circle
			(at -19.949922 18.050002)
			(size 0.4572 0.4572)
			(layers "F.Cu" "F.Mask" "F.Paste")
			(net "GND")
		)
		(pad "BD5" smd circle
			(at -18.999962 18.050002)
			(size 0.4572 0.4572)
			(layers "F.Cu" "F.Mask" "F.Paste")
			(net "Net_1672")
		)
		(pad "BD6" smd circle
			(at -18.050002 18.050002)
			(size 0.4572 0.4572)
			(layers "F.Cu" "F.Mask" "F.Paste")
			(net "GND")
		)
		(pad "BD7" smd circle
			(at -17.100042 18.050002)
			(size 0.4572 0.4572)
			(layers "F.Cu" "F.Mask" "F.Paste")
			(net "Net_1651")
		)
		(pad "BD8" smd circle
			(at -16.150082 18.050002)
			(size 0.4572 0.4572)
			(layers "F.Cu" "F.Mask" "F.Paste")
			(net "GND")
		)
		(pad "BD9" smd circle
			(at -15.200122 18.050002)
			(size 0.4572 0.4572)
			(layers "F.Cu" "F.Mask" "F.Paste")
			(net "P5E_PEX1_STN2_TX_DN<47>")
		)
		(pad "BD10" smd circle
			(at -14.249908 18.050002)
			(size 0.4572 0.4572)
			(layers "F.Cu" "F.Mask" "F.Paste")
			(net "GND")
		)
		(pad "BD11" smd circle
			(at -13.299948 18.050002)
			(size 0.4572 0.4572)
			(layers "F.Cu" "F.Mask" "F.Paste")
			(net "P5E_PEX1_STN2_TX_DN<45>")
		)
		(pad "BD12" smd circle
			(at -12.349988 18.050002)
			(size 0.4572 0.4572)
			(layers "F.Cu" "F.Mask" "F.Paste")
			(net "GND")
		)
		(pad "BD13" smd circle
			(at -11.400028 18.050002)
			(size 0.4572 0.4572)
			(layers "F.Cu" "F.Mask" "F.Paste")
			(net "P5E_PEX1_STN2_TX_DN<43>")
		)
		(pad "BD14" smd circle
			(at -10.450068 18.050002)
			(size 0.4572 0.4572)
			(layers "F.Cu" "F.Mask" "F.Paste")
			(net "GND")
		)
		(pad "BD15" smd circle
			(at -9.500108 18.050002)
			(size 0.4572 0.4572)
			(layers "F.Cu" "F.Mask" "F.Paste")
			(net "P5E_PEX1_STN2_TX_DN<41>")
		)
		(pad "BD16" smd circle
			(at -8.549894 18.050002)
			(size 0.4572 0.4572)
			(layers "F.Cu" "F.Mask" "F.Paste")
			(net "GND")
		)
		(pad "BD17" smd circle
			(at -7.599934 18.050002)
			(size 0.4572 0.4572)
			(layers "F.Cu" "F.Mask" "F.Paste")
			(net "P5E_PEX1_STN2_TX_DN<39>")
		)
		(pad "BD18" smd circle
			(at -6.649974 18.050002)
			(size 0.4572 0.4572)
			(layers "F.Cu" "F.Mask" "F.Paste")
			(net "GND")
		)
		(pad "BD19" smd circle
			(at -5.700014 18.050002)
			(size 0.4572 0.4572)
			(layers "F.Cu" "F.Mask" "F.Paste")
			(net "P5E_PEX1_STN2_TX_DN<37>")
		)
		(pad "BD20" smd circle
			(at -4.750054 18.050002)
			(size 0.4572 0.4572)
			(layers "F.Cu" "F.Mask" "F.Paste")
			(net "GND")
		)
		(pad "BD21" smd circle
			(at -3.800094 18.050002)
			(size 0.4572 0.4572)
			(layers "F.Cu" "F.Mask" "F.Paste")
			(net "P5E_PEX1_STN2_TX_DN<35>")
		)
		(pad "BD22" smd circle
			(at -2.84988 18.050002)
			(size 0.4572 0.4572)
			(layers "F.Cu" "F.Mask" "F.Paste")
			(net "GND")
		)
		(pad "BD23" smd circle
			(at -1.89992 18.050002)
			(size 0.4572 0.4572)
			(layers "F.Cu" "F.Mask" "F.Paste")
			(net "P5E_PEX1_STN2_TX_DN<33>")
		)
		(pad "BD24" smd circle
			(at -0.94996 18.050002)
			(size 0.4572 0.4572)
			(layers "F.Cu" "F.Mask" "F.Paste")
			(net "GND")
		)
		(pad "BD25" smd circle
			(at 0 18.050002)
			(size 0.4572 0.4572)
			(layers "F.Cu" "F.Mask" "F.Paste")
			(net "P5E_PEX1_STN1_TX_DN<16>")
		)
		(pad "BD26" smd circle
			(at 0.94996 18.050002)
			(size 0.4572 0.4572)
			(layers "F.Cu" "F.Mask" "F.Paste")
			(net "GND")
		)
		(pad "BD27" smd circle
			(at 1.89992 18.050002)
			(size 0.4572 0.4572)
			(layers "F.Cu" "F.Mask" "F.Paste")
			(net "P5E_PEX1_STN1_TX_DN<18>")
		)
		(pad "BD28" smd circle
			(at 2.84988 18.050002)
			(size 0.4572 0.4572)
			(layers "F.Cu" "F.Mask" "F.Paste")
			(net "GND")
		)
		(pad "BD29" smd circle
			(at 3.800094 18.050002)
			(size 0.4572 0.4572)
			(layers "F.Cu" "F.Mask" "F.Paste")
			(net "P5E_PEX1_STN1_TX_DN<20>")
		)
		(pad "BD30" smd circle
			(at 4.750054 18.050002)
			(size 0.4572 0.4572)
			(layers "F.Cu" "F.Mask" "F.Paste")
			(net "GND")
		)
		(pad "BD31" smd circle
			(at 5.700014 18.050002)
			(size 0.4572 0.4572)
			(layers "F.Cu" "F.Mask" "F.Paste")
			(net "P5E_PEX1_STN1_TX_DN<22>")
		)
		(pad "BD32" smd circle
			(at 6.649974 18.050002)
			(size 0.4572 0.4572)
			(layers "F.Cu" "F.Mask" "F.Paste")
			(net "GND")
		)
		(pad "BD33" smd circle
			(at 7.599934 18.050002)
			(size 0.4572 0.4572)
			(layers "F.Cu" "F.Mask" "F.Paste")
			(net "P5E_PEX1_STN1_TX_DN<24>")
		)
		(pad "BD34" smd circle
			(at 8.549894 18.050002)
			(size 0.4572 0.4572)
			(layers "F.Cu" "F.Mask" "F.Paste")
			(net "GND")
		)
		(pad "BD35" smd circle
			(at 9.500108 18.050002)
			(size 0.4572 0.4572)
			(layers "F.Cu" "F.Mask" "F.Paste")
			(net "P5E_PEX1_STN1_TX_DN<26>")
		)
		(pad "BD36" smd circle
			(at 10.450068 18.050002)
			(size 0.4572 0.4572)
			(layers "F.Cu" "F.Mask" "F.Paste")
			(net "GND")
		)
		(pad "BD37" smd circle
			(at 11.400028 18.050002)
			(size 0.4572 0.4572)
			(layers "F.Cu" "F.Mask" "F.Paste")
			(net "P5E_PEX1_STN1_TX_DN<28>")
		)
		(pad "BD38" smd circle
			(at 12.349988 18.050002)
			(size 0.4572 0.4572)
			(layers "F.Cu" "F.Mask" "F.Paste")
			(net "GND")
		)
		(pad "BD39" smd circle
			(at 13.299948 18.050002)
			(size 0.4572 0.4572)
			(layers "F.Cu" "F.Mask" "F.Paste")
			(net "P5E_PEX1_STN1_TX_DN<30>")
		)
		(pad "BD40" smd circle
			(at 14.249908 18.050002)
			(size 0.4572 0.4572)
			(layers "F.Cu" "F.Mask" "F.Paste")
			(net "GND")
		)
		(pad "BD41" smd circle
			(at 15.200122 18.050002)
			(size 0.4572 0.4572)
			(layers "F.Cu" "F.Mask" "F.Paste")
			(net "P5E_PEX1_STN0_TX_DN<15>")
		)
		(pad "BD42" smd circle
			(at 16.150082 18.050002)
			(size 0.4572 0.4572)
			(layers "F.Cu" "F.Mask" "F.Paste")
			(net "GND")
		)
		(pad "BD43" smd circle
			(at 17.100042 18.050002)
			(size 0.4572 0.4572)
			(layers "F.Cu" "F.Mask" "F.Paste")
			(net "P5E_PEX1_STN0_TX_DN<13>")
		)
		(pad "BD44" smd circle
			(at 18.050002 18.050002)
			(size 0.4572 0.4572)
			(layers "F.Cu" "F.Mask" "F.Paste")
			(net "GND")
		)
		(pad "BD45" smd circle
			(at 18.999962 18.050002)
			(size 0.4572 0.4572)
			(layers "F.Cu" "F.Mask" "F.Paste")
			(net "P5E_PEX1_STN0_TX_DN<11>")
		)
		(pad "BD46" smd circle
			(at 19.949922 18.050002)
			(size 0.4572 0.4572)
			(layers "F.Cu" "F.Mask" "F.Paste")
			(net "GND")
		)
		(pad "BD47" smd circle
			(at 20.899882 18.050002)
			(size 0.4572 0.4572)
			(layers "F.Cu" "F.Mask" "F.Paste")
			(net "P5E_PEX1_STN0_TX_DN<9>")
		)
		(pad "BD48" smd circle
			(at 21.850096 18.050002)
			(size 0.4572 0.4572)
			(layers "F.Cu" "F.Mask" "F.Paste")
			(net "GND")
		)
		(pad "BD49" smd circle
			(at 22.800056 18.050002)
			(size 0.4572 0.4572)
			(layers "F.Cu" "F.Mask" "F.Paste")
			(net "GND")
		)
		(pad "BE1" smd circle
			(at -22.800056 18.999962)
			(size 0.4572 0.4572)
			(layers "F.Cu" "F.Mask" "F.Paste")
			(net "Net_1648")
		)
		(pad "BE2" smd circle
			(at -21.850096 18.999962)
			(size 0.4572 0.4572)
			(layers "F.Cu" "F.Mask" "F.Paste")
			(net "Net_1645")
		)
		(pad "BE3" smd circle
			(at -20.899882 18.999962)
			(size 0.4572 0.4572)
			(layers "F.Cu" "F.Mask" "F.Paste")
			(net "GND")
		)
		(pad "BE4" smd circle
			(at -19.949922 18.999962)
			(size 0.4572 0.4572)
			(layers "F.Cu" "F.Mask" "F.Paste")
			(net "GND")
		)
		(pad "BE5" smd circle
			(at -18.999962 18.999962)
			(size 0.4572 0.4572)
			(layers "F.Cu" "F.Mask" "F.Paste")
			(net "GND")
		)
		(pad "BE6" smd circle
			(at -18.050002 18.999962)
			(size 0.4572 0.4572)
			(layers "F.Cu" "F.Mask" "F.Paste")
			(net "GND")
		)
		(pad "BE7" smd circle
			(at -17.100042 18.999962)
			(size 0.4572 0.4572)
			(layers "F.Cu" "F.Mask" "F.Paste")
			(net "GND")
		)
		(pad "BE8" smd circle
			(at -16.150082 18.999962)
			(size 0.4572 0.4572)
			(layers "F.Cu" "F.Mask" "F.Paste")
			(net "GND")
		)
		(pad "BE9" smd circle
			(at -15.200122 18.999962)
			(size 0.4572 0.4572)
			(layers "F.Cu" "F.Mask" "F.Paste")
			(net "GND")
		)
		(pad "BE10" smd circle
			(at -14.249908 18.999962)
			(size 0.4572 0.4572)
			(layers "F.Cu" "F.Mask" "F.Paste")
			(net "GND")
		)
		(pad "BE11" smd circle
			(at -13.299948 18.999962)
			(size 0.4572 0.4572)
			(layers "F.Cu" "F.Mask" "F.Paste")
			(net "GND")
		)
		(pad "BE12" smd circle
			(at -12.349988 18.999962)
			(size 0.4572 0.4572)
			(layers "F.Cu" "F.Mask" "F.Paste")
			(net "GND")
		)
		(pad "BE13" smd circle
			(at -11.400028 18.999962)
			(size 0.4572 0.4572)
			(layers "F.Cu" "F.Mask" "F.Paste")
			(net "GND")
		)
		(pad "BE14" smd circle
			(at -10.450068 18.999962)
			(size 0.4572 0.4572)
			(layers "F.Cu" "F.Mask" "F.Paste")
			(net "GND")
		)
		(pad "BE15" smd circle
			(at -9.500108 18.999962)
			(size 0.4572 0.4572)
			(layers "F.Cu" "F.Mask" "F.Paste")
			(net "GND")
		)
		(pad "BE16" smd circle
			(at -8.549894 18.999962)
			(size 0.4572 0.4572)
			(layers "F.Cu" "F.Mask" "F.Paste")
			(net "GND")
		)
		(pad "BE17" smd circle
			(at -7.599934 18.999962)
			(size 0.4572 0.4572)
			(layers "F.Cu" "F.Mask" "F.Paste")
			(net "GND")
		)
		(pad "BE18" smd circle
			(at -6.649974 18.999962)
			(size 0.4572 0.4572)
			(layers "F.Cu" "F.Mask" "F.Paste")
			(net "GND")
		)
		(pad "BE19" smd circle
			(at -5.700014 18.999962)
			(size 0.4572 0.4572)
			(layers "F.Cu" "F.Mask" "F.Paste")
			(net "GND")
		)
		(pad "BE20" smd circle
			(at -4.750054 18.999962)
			(size 0.4572 0.4572)
			(layers "F.Cu" "F.Mask" "F.Paste")
			(net "GND")
		)
		(pad "BE21" smd circle
			(at -3.800094 18.999962)
			(size 0.4572 0.4572)
			(layers "F.Cu" "F.Mask" "F.Paste")
			(net "GND")
		)
		(pad "BE22" smd circle
			(at -2.84988 18.999962)
			(size 0.4572 0.4572)
			(layers "F.Cu" "F.Mask" "F.Paste")
			(net "GND")
		)
		(pad "BE23" smd circle
			(at -1.89992 18.999962)
			(size 0.4572 0.4572)
			(layers "F.Cu" "F.Mask" "F.Paste")
			(net "GND")
		)
		(pad "BE24" smd circle
			(at -0.94996 18.999962)
			(size 0.4572 0.4572)
			(layers "F.Cu" "F.Mask" "F.Paste")
			(net "GND")
		)
		(pad "BE25" smd circle
			(at 0 18.999962)
			(size 0.4572 0.4572)
			(layers "F.Cu" "F.Mask" "F.Paste")
			(net "GND")
		)
		(pad "BE26" smd circle
			(at 0.94996 18.999962)
			(size 0.4572 0.4572)
			(layers "F.Cu" "F.Mask" "F.Paste")
			(net "GND")
		)
		(pad "BE27" smd circle
			(at 1.89992 18.999962)
			(size 0.4572 0.4572)
			(layers "F.Cu" "F.Mask" "F.Paste")
			(net "GND")
		)
		(pad "BE28" smd circle
			(at 2.84988 18.999962)
			(size 0.4572 0.4572)
			(layers "F.Cu" "F.Mask" "F.Paste")
			(net "GND")
		)
		(pad "BE29" smd circle
			(at 3.800094 18.999962)
			(size 0.4572 0.4572)
			(layers "F.Cu" "F.Mask" "F.Paste")
			(net "GND")
		)
		(pad "BE30" smd circle
			(at 4.750054 18.999962)
			(size 0.4572 0.4572)
			(layers "F.Cu" "F.Mask" "F.Paste")
			(net "GND")
		)
		(pad "BE31" smd circle
			(at 5.700014 18.999962)
			(size 0.4572 0.4572)
			(layers "F.Cu" "F.Mask" "F.Paste")
			(net "GND")
		)
		(pad "BE32" smd circle
			(at 6.649974 18.999962)
			(size 0.4572 0.4572)
			(layers "F.Cu" "F.Mask" "F.Paste")
			(net "GND")
		)
		(pad "BE33" smd circle
			(at 7.599934 18.999962)
			(size 0.4572 0.4572)
			(layers "F.Cu" "F.Mask" "F.Paste")
			(net "GND")
		)
		(pad "BE34" smd circle
			(at 8.549894 18.999962)
			(size 0.4572 0.4572)
			(layers "F.Cu" "F.Mask" "F.Paste")
			(net "GND")
		)
		(pad "BE35" smd circle
			(at 9.500108 18.999962)
			(size 0.4572 0.4572)
			(layers "F.Cu" "F.Mask" "F.Paste")
			(net "GND")
		)
	)
)
